(kicad_pcb
	(version 20241229)
	(generator "pcbnew")
	(generator_version "9.0")
	(general
		(thickness 1.61)
		(legacy_teardrops no)
	)
	(paper "A3")
	(title_block
		(title "RDIMM DDR5 Tester")
		(date "2026-05-21")
		(rev "2.2.0")
		(company "Antmicro")
		(comment 9 "footprints 219-222 of 796")
	)
	(layers
		(0 "F.Cu" signal)
		(4 "In1.Cu" power)
		(6 "In2.Cu" mixed)
		(8 "In3.Cu" power)
		(10 "In4.Cu" mixed)
		(12 "In5.Cu" power)
		(14 "In6.Cu" mixed)
		(16 "In7.Cu" power)
		(18 "In8.Cu" power)
		(20 "In9.Cu" mixed)
		(22 "In10.Cu" power)
		(2 "B.Cu" signal)
		(9 "F.Adhes" user "F.Adhesive")
		(11 "B.Adhes" user "B.Adhesive")
		(13 "F.Paste" user)
		(15 "B.Paste" user)
		(5 "F.SilkS" user "F.Silkscreen")
		(7 "B.SilkS" user "B.Silkscreen")
		(1 "F.Mask" user)
		(3 "B.Mask" user)
		(17 "Dwgs.User" user "User.Drawings")
		(19 "Cmts.User" user "User.Comments")
		(21 "Eco1.User" user "User.Eco1")
		(23 "Eco2.User" user "User.Eco2")
		(25 "Edge.Cuts" user)
		(27 "Margin" user)
		(31 "F.CrtYd" user "F.Courtyard")
		(29 "B.CrtYd" user "B.Courtyard")
		(35 "F.Fab" user)
		(33 "B.Fab" user)
	)
	(footprint "antmicro-footprints:SC70-3"
		(layer "F.Cu")
		(at 250.269499 132.394)
		(property "Reference" "Q14"
			(at 0.490501 1.096 90)
			(layer "F.SilkS")
			(effects
				(font
					(size 0.7 0.7)
					(thickness 0.15)
				)
				(justify left bottom)
			)
		)
		(property "Value" "BSS138PW"
			(at 0 2.3 0)
			(layer "F.Fab")
			(effects
				(font
					(size 0.7 0.7)
					(thickness 0.15)
				)
				(justify left bottom)
			)
		)
		(property "Datasheet" "https://assets.nexperia.com/documents/data-sheet/BSS138PW.pdf"
			(at 0 0 0)
			(layer "F.Fab")
			(hide yes)
			(effects
				(font
					(size 1.27 1.27)
					(thickness 0.15)
				)
			)
		)
		(property "MPN" "BSS138PW"
			(at 0 0 0)
			(unlocked yes)
			(layer "F.Fab")
			(hide yes)
			(effects
				(font
					(size 1 1)
					(thickness 0.15)
				)
			)
		)
		(property "Manufacturer" "Nexperia"
			(at 0 0 0)
			(unlocked yes)
			(layer "F.Fab")
			(hide yes)
			(effects
				(font
					(size 1 1)
					(thickness 0.15)
				)
			)
		)
		(property "Author" "Antmicro"
			(at 0 0 0)
			(unlocked yes)
			(layer "F.Fab")
			(hide yes)
			(effects
				(font
					(size 1 1)
					(thickness 0.15)
				)
			)
		)
		(property "License" "Apache-2.0"
			(at 0 0 0)
			(unlocked yes)
			(layer "F.Fab")
			(hide yes)
			(effects
				(font
					(size 1 1)
					(thickness 0.15)
				)
			)
		)
		(sheetname "/Supply/")
		(sheetfile "supply.kicad_sch")
		(attr smd)
		(fp_line
			(start -0.3 -1)
			(end 0.627 -0.999)
			(stroke
				(width 0.15)
				(type solid)
			)
			(layer "F.SilkS")
		)
		(fp_line
			(start -0.3 1)
			(end 0.627 1.001)
			(stroke
				(width 0.15)
				(type solid)
			)
			(layer "F.SilkS")
		)
		(fp_line
			(start 0.627 -0.6)
			(end 0.627 -0.999)
			(stroke
				(width 0.15)
				(type solid)
			)
			(layer "F.SilkS")
		)
		(fp_line
			(start 0.627 0.6)
			(end 0.627 1.001)
			(stroke
				(width 0.15)
				(type solid)
			)
			(layer "F.SilkS")
		)
		(fp_line
			(start -1.4 1)
			(end -1.4 -1)
			(stroke
				(width 0.05)
				(type solid)
			)
			(layer "F.CrtYd")
		)
		(fp_line
			(start -0.9 -1.3)
			(end -0.9 -1)
			(stroke
				(width 0.05)
				(type solid)
			)
			(layer "F.CrtYd")
		)
		(fp_line
			(start -0.9 -1.3)
			(end 0.9 -1.3)
			(stroke
				(width 0.05)
				(type solid)
			)
			(layer "F.CrtYd")
		)
		(fp_line
			(start -0.9 -1)
			(end -1.4 -1)
			(stroke
				(width 0.05)
				(type solid)
			)
			(layer "F.CrtYd")
		)
		(fp_line
			(start -0.9 1)
			(end -1.4 1)
			(stroke
				(width 0.05)
				(type solid)
			)
			(layer "F.CrtYd")
		)
		(fp_line
			(start -0.9 1.3)
			(end -0.9 1)
			(stroke
				(width 0.05)
				(type solid)
			)
			(layer "F.CrtYd")
		)
		(fp_line
			(start 0.9 -1.3)
			(end 0.9 -0.4)
			(stroke
				(width 0.05)
				(type solid)
			)
			(layer "F.CrtYd")
		)
		(fp_line
			(start 0.9 -0.4)
			(end 1.4 -0.4)
			(stroke
				(width 0.05)
				(type solid)
			)
			(layer "F.CrtYd")
		)
		(fp_line
			(start 0.9 0.4)
			(end 0.9 1.3)
			(stroke
				(width 0.05)
				(type solid)
			)
			(layer "F.CrtYd")
		)
		(fp_line
			(start 0.9 1.3)
			(end -0.9 1.3)
			(stroke
				(width 0.05)
				(type solid)
			)
			(layer "F.CrtYd")
		)
		(fp_line
			(start 1.4 -0.4)
			(end 1.4 0.4)
			(stroke
				(width 0.05)
				(type solid)
			)
			(layer "F.CrtYd")
		)
		(fp_line
			(start 1.4 0.4)
			(end 0.9 0.4)
			(stroke
				(width 0.05)
				(type solid)
			)
			(layer "F.CrtYd")
		)
		(fp_rect
			(start -0.623 -0.999)
			(end 0.627 1.001)
			(stroke
				(width 0.15)
				(type solid)
			)
			(fill no)
			(layer "F.Fab")
		)
		(fp_text user "License: Apache-2.0"
			(at -1.45 6.782 0)
			(layer "F.Fab")
			(effects
				(font
					(size 0.7 0.7)
					(thickness 0.15)
				)
				(justify left bottom)
			)
		)
		(fp_text user "${REFERENCE}"
			(at -1.45 4.783 0)
			(layer "F.Fab")
			(effects
				(font
					(size 0.7 0.7)
					(thickness 0.15)
				)
				(justify left bottom)
			)
		)
		(fp_text user "Author: Antmicro"
			(at -1.45 5.782 0)
			(layer "F.Fab")
			(effects
				(font
					(size 0.7 0.7)
					(thickness 0.15)
				)
				(justify left bottom)
			)
		)
		(pad "1" smd rect
			(at -1.051 -0.65 90)
			(size 0.6 0.6)
			(layers "F.Cu" "F.Mask" "F.Paste")
			(net 185 "FPGA_POWER_OFF")
			(pinfunction "G")
			(pintype "passive")
		)
		(pad "2" smd rect
			(at -1.051 0.65 90)
			(size 0.6 0.6)
			(layers "F.Cu" "F.Mask" "F.Paste")
			(net 1 "GND")
			(pinfunction "S")
			(pintype "passive")
		)
		(pad "3" smd rect
			(at 1.05 0 90)
			(size 0.6 0.6)
			(layers "F.Cu" "F.Mask" "F.Paste")
			(net 137 "/Supply/~{PB_CTRL_CLR}")
			(pinfunction "D")
			(pintype "passive")
		)
	)
	(footprint "antmicro-footprints:LED_0603_1608Metric_G"
		(layer "F.Cu")
		(at 105.305 102.225 90)
		(descr "LED SMD 0603 Green")
		(tags "LED SMD 0603 Green")
		(property "Reference" "D7"
			(at -2.575 -0.305 90)
			(layer "F.SilkS")
			(hide yes)
			(effects
				(font
					(size 0.7 0.7)
					(thickness 0.15)
				)
				(justify left bottom)
			)
		)
		(property "Value" "LED_G_0603_KP-1608CGCK"
			(at -0.001 1.599 90)
			(layer "F.Fab")
			(effects
				(font
					(size 0.7 0.7)
					(thickness 0.15)
				)
				(justify left bottom)
			)
		)
		(property "Datasheet" "http://www.kingbright.com/attachments/file/psearch//000/00/00/KP-1608CGCK(Ver.23B).pdf"
			(at 0 0 90)
			(layer "F.Fab")
			(hide yes)
			(effects
				(font
					(size 1.27 1.27)
					(thickness 0.15)
				)
			)
		)
		(property "MPN" "KP-1608CGCK"
			(at 0 0 90)
			(unlocked yes)
			(layer "F.Fab")
			(hide yes)
			(effects
				(font
					(size 1 1)
					(thickness 0.15)
				)
			)
		)
		(property "Manufacturer" "Kingbright"
			(at 0 0 90)
			(unlocked yes)
			(layer "F.Fab")
			(hide yes)
			(effects
				(font
					(size 1 1)
					(thickness 0.15)
				)
			)
		)
		(property "Author" "Antmicro"
			(at 0 0 90)
			(unlocked yes)
			(layer "F.Fab")
			(hide yes)
			(effects
				(font
					(size 1 1)
					(thickness 0.15)
				)
			)
		)
		(property "License" "Apache-2.0"
			(at 0 0 90)
			(unlocked yes)
			(layer "F.Fab")
			(hide yes)
			(effects
				(font
					(size 1 1)
					(thickness 0.15)
				)
			)
		)
		(property "Color" "Green"
			(at 0 0 90)
			(unlocked yes)
			(layer "F.Fab")
			(hide yes)
			(effects
				(font
					(size 1 1)
					(thickness 0.15)
				)
			)
		)
		(sheetname "/FPGA banks HD/")
		(sheetfile "fpga-hd-banks.kicad_sch")
		(attr smd)
		(fp_line
			(start 0.22 -0.35)
			(end -0.22 -0.35)
			(stroke
				(width 0.15)
				(type solid)
			)
			(layer "F.SilkS")
		)
		(fp_line
			(start -1.18 -0.319)
			(end -1.18 0.321)
			(stroke
				(width 0.15)
				(type solid)
			)
			(layer "F.SilkS")
		)
		(fp_line
			(start 0.105328 0.001008)
			(end 0.24 0.001)
			(stroke
				(width 0.1)
				(type solid)
			)
			(layer "F.SilkS")
		)
		(fp_line
			(start -0.094672 0.001008)
			(end 0.105328 -0.198992)
			(stroke
				(width 0.1)
				(type solid)
			)
			(layer "F.SilkS")
		)
		(fp_line
			(start -0.094672 0.001008)
			(end -0.24 0.001008)
			(stroke
				(width 0.1)
				(type solid)
			)
			(layer "F.SilkS")
		)
		(fp_line
			(start 0.105328 0.201008)
			(end 0.105328 -0.198992)
			(stroke
				(width 0.1)
				(type solid)
			)
			(layer "F.SilkS")
		)
		(fp_line
			(start 0.105328 0.201008)
			(end -0.094672 0.001008)
			(stroke
				(width 0.1)
				(type solid)
			)
			(layer "F.SilkS")
		)
		(fp_line
			(start -0.094672 0.201008)
			(end -0.094672 -0.198992)
			(stroke
				(width 0.1)
				(type solid)
			)
			(layer "F.SilkS")
		)
		(fp_line
			(start 0.22 0.35)
			(end -0.22 0.35)
			(stroke
				(width 0.15)
				(type solid)
			)
			(layer "F.SilkS")
		)
		(fp_rect
			(start 1.25 0.65)
			(end -1.25 -0.65)
			(stroke
				(width 0.05)
				(type solid)
			)
			(fill no)
			(layer "F.CrtYd")
		)
		(fp_line
			(start 0.201 -0.202)
			(end -0.101 0)
			(stroke
				(width 0.15)
				(type solid)
			)
			(layer "F.Fab")
		)
		(fp_line
			(start -0.199 -0.202)
			(end -0.199 0.1)
			(stroke
				(width 0.15)
				(type solid)
			)
			(layer "F.Fab")
		)
		(fp_line
			(start 0.599 0)
			(end 0.201 0)
			(stroke
				(width 0.15)
				(type solid)
			)
			(layer "F.Fab")
		)
		(fp_line
			(start 0.201 0)
			(end 0.201 -0.202)
			(stroke
				(width 0.15)
				(type solid)
			)
			(layer "F.Fab")
		)
		(fp_line
			(start -0.101 0)
			(end 0.201 0.2)
			(stroke
				(width 0.15)
				(type solid)
			)
			(layer "F.Fab")
		)
		(fp_line
			(start -0.199 0)
			(end -0.597 0)
			(stroke
				(width 0.15)
				(type solid)
			)
			(layer "F.Fab")
		)
		(fp_line
			(start 0.201 0.2)
			(end 0.201 0)
			(stroke
				(width 0.15)
				(type solid)
			)
			(layer "F.Fab")
		)
		(fp_line
			(start -0.199 0.2)
			(end -0.199 0.1)
			(stroke
				(width 0.15)
				(type solid)
			)
			(layer "F.Fab")
		)
		(fp_rect
			(start 0.848 0.4)
			(end -0.85 -0.402)
			(stroke
				(width 0.15)
				(type solid)
			)
			(fill no)
			(layer "F.Fab")
		)
		(fp_text user "${REFERENCE}"
			(at -1.4224 5.999 90)
			(layer "F.Fab")
			(effects
				(font
					(size 0.7 0.7)
					(thickness 0.15)
				)
				(justify left bottom)
			)
		)
		(fp_text user "License: Apache-2.0"
			(at -1.4224 3.599 90)
			(layer "F.Fab")
			(effects
				(font
					(size 0.7 0.7)
					(thickness 0.15)
				)
				(justify left bottom)
			)
		)
		(fp_text user "Author: Antmicro"
			(at -1.4224 4.799 90)
			(layer "F.Fab")
			(effects
				(font
					(size 0.7 0.7)
					(thickness 0.15)
				)
				(justify left bottom)
			)
		)
		(pad "1" smd roundrect
			(at -0.7 0 270)
			(size 0.8 1)
			(layers "F.Cu" "F.Mask" "F.Paste")
			(roundrect_rratio 0.2)
			(net 151 "+3V3")
			(pinfunction "C")
			(pintype "passive")
		)
		(pad "2" smd roundrect
			(at 0.7 0 270)
			(size 0.8 1)
			(layers "F.Cu" "F.Mask" "F.Paste")
			(roundrect_rratio 0.2)
			(net 232 "Net-(D7-A)")
			(pinfunction "A")
			(pintype "passive")
		)
	)
	(footprint "antmicro-footprints:R_0402_1005Metric"
		(layer "F.Cu")
		(at 251.95 182.078 -90)
		(descr "Resistor SMD 0402")
		(tags "resistor SMD 0402")
		(property "Reference" "R96"
			(at -1.278 2.55 90)
			(layer "F.SilkS")
			(effects
				(font
					(size 0.7 0.7)
					(thickness 0.15)
				)
				(justify right bottom)
			)
		)
		(property "Value" "R_0R_0402"
			(at -1.011843 1.772047 90)
			(layer "F.Fab")
			(effects
				(font
					(size 0.7 0.7)
					(thickness 0.15)
				)
				(justify right bottom)
			)
		)
		(property "Datasheet" "https://industrial.panasonic.com/cdbs/www-data/pdf/RDA0000/AOA0000C301.pdf"
			(at 0 0 270)
			(layer "F.Fab")
			(hide yes)
			(effects
				(font
					(size 1.27 1.27)
					(thickness 0.15)
				)
			)
		)
		(property "MPN" "ERJ2GE0R00X"
			(at 0 0 270)
			(unlocked yes)
			(layer "F.Fab")
			(hide yes)
			(effects
				(font
					(size 1 1)
					(thickness 0.15)
				)
			)
		)
		(property "Manufacturer" "Panasonic"
			(at 0 0 270)
			(unlocked yes)
			(layer "F.Fab")
			(hide yes)
			(effects
				(font
					(size 1 1)
					(thickness 0.15)
				)
			)
		)
		(property "License" "Apache-2.0"
			(at 0 0 270)
			(unlocked yes)
			(layer "F.Fab")
			(hide yes)
			(effects
				(font
					(size 1 1)
					(thickness 0.15)
				)
			)
		)
		(property "Author" "Antmicro"
			(at 0 0 270)
			(unlocked yes)
			(layer "F.Fab")
			(hide yes)
			(effects
				(font
					(size 1 1)
					(thickness 0.15)
				)
			)
		)
		(property "Val" "0R"
			(at 0 0 270)
			(unlocked yes)
			(layer "F.Fab")
			(hide yes)
			(effects
				(font
					(size 1 1)
					(thickness 0.15)
				)
			)
		)
		(property "Tolerance" "~"
			(at 0 0 270)
			(unlocked yes)
			(layer "F.Fab")
			(hide yes)
			(effects
				(font
					(size 1 1)
					(thickness 0.15)
				)
			)
		)
		(property "Current" "1A"
			(at 0 0 270)
			(unlocked yes)
			(layer "F.Fab")
			(hide yes)
			(effects
				(font
					(size 1 1)
					(thickness 0.15)
				)
			)
		)
		(sheetname "/I^{2}C + I3C/")
		(sheetfile "i2c.kicad_sch")
		(attr smd exclude_from_bom dnp)
		(fp_rect
			(start -0.925 -0.47)
			(end 0.925 0.47)
			(stroke
				(width 0.05)
				(type default)
			)
			(fill no)
			(layer "F.CrtYd")
		)
		(fp_rect
			(start -0.5 -0.25)
			(end 0.5 0.25)
			(stroke
				(width 0.15)
				(type solid)
			)
			(fill no)
			(layer "F.Fab")
		)
		(fp_text user "Author: Antmicro"
			(at -0.95 4.169 270)
			(layer "F.Fab")
			(effects
				(font
					(size 0.7 0.7)
					(thickness 0.15)
				)
				(justify left bottom)
			)
		)
		(fp_text user "${REFERENCE}"
			(at -0.95 3.168 270)
			(layer "F.Fab")
			(effects
				(font
					(size 0.7 0.7)
					(thickness 0.15)
				)
				(justify left bottom)
			)
		)
		(fp_text user "License: Apache-2.0"
			(at -0.95 5.169 270)
			(layer "F.Fab")
			(effects
				(font
					(size 0.7 0.7)
					(thickness 0.15)
				)
				(justify left bottom)
			)
		)
		(pad "1" smd roundrect
			(at -0.48 0 270)
			(size 0.59 0.64)
			(layers "F.Cu" "F.Mask" "F.Paste")
			(roundrect_rratio 0.25)
			(net 775 "Net-(Q24-S)")
			(pintype "passive")
		)
		(pad "2" smd roundrect
			(at 0.48 0 270)
			(size 0.59 0.64)
			(layers "F.Cu" "F.Mask" "F.Paste")
			(roundrect_rratio 0.25)
			(net 151 "+3V3")
			(pintype "passive")
		)
	)
	(footprint "antmicro-footprints:R_0402_1005Metric"
		(layer "F.Cu")
		(at 248.169499 135.194 90)
		(descr "Resistor SMD 0402")
		(tags "resistor SMD 0402")
		(property "Reference" "R171"
			(at -1.356 -0.772697 90)
			(layer "F.SilkS")
			(effects
				(font
					(size 0.7 0.7)
					(thickness 0.15)
				)
				(justify left bottom)
			)
		)
		(property "Value" "R_47k_0402"
			(at -1.011843 1.772047 90)
			(layer "F.Fab")
			(effects
				(font
					(size 0.7 0.7)
					(thickness 0.15)
				)
				(justify left bottom)
			)
		)
		(property "Datasheet" "https://www.bourns.com/docs/product-datasheets/cr.pdf"
			(at 0 0 90)
			(layer "F.Fab")
			(hide yes)
			(effects
				(font
					(size 1.27 1.27)
					(thickness 0.15)
				)
			)
		)
		(property "Manufacturer" "Bourns"
			(at 0 0 90)
			(unlocked yes)
			(layer "F.Fab")
			(hide yes)
			(effects
				(font
					(size 1 1)
					(thickness 0.15)
				)
			)
		)
		(property "MPN" "CR0402-FX-4702GLF"
			(at 0 0 90)
			(unlocked yes)
			(layer "F.Fab")
			(hide yes)
			(effects
				(font
					(size 1 1)
					(thickness 0.15)
				)
			)
		)
		(property "Val" "47k"
			(at 0 0 90)
			(unlocked yes)
			(layer "F.Fab")
			(hide yes)
			(effects
				(font
					(size 1 1)
					(thickness 0.15)
				)
			)
		)
		(property "License" "Apache-2.0"
			(at 0 0 90)
			(unlocked yes)
			(layer "F.Fab")
			(hide yes)
			(effects
				(font
					(size 1 1)
					(thickness 0.15)
				)
			)
		)
		(property "Author" "Antmicro"
			(at 0 0 90)
			(unlocked yes)
			(layer "F.Fab")
			(hide yes)
			(effects
				(font
					(size 1 1)
					(thickness 0.15)
				)
			)
		)
		(property "Tolerance" "1%"
			(at 0 0 90)
			(unlocked yes)
			(layer "F.Fab")
			(hide yes)
			(effects
				(font
					(size 1 1)
					(thickness 0.15)
				)
			)
		)
		(sheetname "/Supply/")
		(sheetfile "supply.kicad_sch")
		(attr smd)
		(fp_rect
			(start -0.925 -0.47)
			(end 0.925 0.47)
			(stroke
				(width 0.05)
				(type default)
			)
			(fill no)
			(layer "F.CrtYd")
		)
		(fp_rect
			(start -0.5 -0.25)
			(end 0.5 0.25)
			(stroke
				(width 0.15)
				(type solid)
			)
			(fill no)
			(layer "F.Fab")
		)
		(fp_text user "Author: Antmicro"
			(at -0.95 4.169 90)
			(layer "F.Fab")
			(effects
				(font
					(size 0.7 0.7)
					(thickness 0.15)
				)
				(justify left bottom)
			)
		)
		(fp_text user "${REFERENCE}"
			(at -0.95 3.168 90)
			(layer "F.Fab")
			(effects
				(font
					(size 0.7 0.7)
					(thickness 0.15)
				)
				(justify left bottom)
			)
		)
		(fp_text user "License: Apache-2.0"
			(at -0.95 5.169 90)
			(layer "F.Fab")
			(effects
				(font
					(size 0.7 0.7)
					(thickness 0.15)
				)
				(justify left bottom)
			)
		)
		(pad "1" smd roundrect
			(at -0.48 0 90)
			(size 0.59 0.64)
			(layers "F.Cu" "F.Mask" "F.Paste")
			(roundrect_rratio 0.25)
			(net 1 "GND")
			(pintype "passive")
		)
		(pad "2" smd roundrect
			(at 0.48 0 90)
			(size 0.59 0.64)
			(layers "F.Cu" "F.Mask" "F.Paste")
			(roundrect_rratio 0.25)
			(net 184 "FPGA_POWER_CYCLE")
			(pintype "passive")
		)
	)
)
